(kicad_pcb
	(version 20260206)
	(generator "pcbnew")
	(generator_version "10.0")
	(general
		(thickness 1.6)
		(legacy_teardrops no)
	)
	(paper "A4")
	(title_block
		(title "Wiwynn_Tioga_Pass_MB.brd")
		(comment 1 "Tioga Pass / footprint 1251 of 4770 (J8A1), pads 1-75 of 77")
	)
	(layers
		(0 "F.Cu" signal "TOP")
		(4 "In1.Cu" signal "L2GND")
		(6 "In2.Cu" signal "L3")
		(8 "In3.Cu" signal "L4GND")
		(10 "In4.Cu" signal "L5")
		(12 "In5.Cu" signal "L6GND")
		(14 "In6.Cu" signal "L7VCC")
		(16 "In7.Cu" signal "L8VCC")
		(18 "In8.Cu" signal "L9GND")
		(20 "In9.Cu" signal "L10")
		(22 "In10.Cu" signal "L11GND")
		(24 "In11.Cu" signal "L12")
		(26 "In12.Cu" signal "L13GND")
		(2 "B.Cu" signal "BOTTOM")
		(9 "F.Adhes" user "F.Adhesive")
		(11 "B.Adhes" user "B.Adhesive")
		(13 "F.Paste" user "Package Geometry/Pastemask Top")
		(15 "B.Paste" user "Package Geometry/Pastemask Bottom")
		(5 "F.SilkS" user "Ref Des/Silkscreen Top")
		(7 "B.SilkS" user "Ref Des/Silkscreen Bottom")
		(1 "F.Mask" user "Board Geometry/Soldermask Top")
		(3 "B.Mask" user "Board Geometry/Soldermask Bottom")
		(17 "Dwgs.User" user "User.Drawings")
		(19 "Cmts.User" user "User.Comments")
		(21 "Eco1.User" user "User.Eco1")
		(23 "Eco2.User" user "User.Eco2")
		(25 "Edge.Cuts" user "Board Geometry/Outline")
		(27 "Margin" user)
		(31 "F.CrtYd" user "Package Geometry/Place Bound Top")
		(29 "B.CrtYd" user "Package Geometry/Place Bound Bottom")
		(35 "F.Fab" user "Ref Des/Assembly Top")
		(33 "B.Fab" user "Ref Des/Assembly Bottom")
	)
	(footprint ""
		(layer "F.Cu")
		(at 430.276 -154.94 -90)
		(property "Reference" "J8A1"
			(at 15.64767 10.287 0)
			(unlocked yes)
			(layer "B.SilkS")
			(effects
				(font
					(size 0.7874 0.5842)
					(thickness 0.1524)
				)
				(justify left mirror)
			)
		)
		(property "Value" ""
			(at 0 0 270)
			(layer "F.Fab")
			(effects
				(font
					(size 1.27 1.27)
				)
			)
		)
		(duplicate_pad_numbers_are_jumpers no)
		(pad "" np_thru_hole circle
			(at -1.329944 -2.990088 270)
			(size 0.254 0.254)
			(drill 2.2098)
			(layers "*.Cu" "*.Mask")
			(clearance 1.2954)
			(thermal_gap 1.2954)
		)
		(pad "" np_thru_hole circle
			(at -1.329944 21.010118 270)
			(size 0.254 0.254)
			(drill 2.2098)
			(layers "*.Cu" "*.Mask")
			(clearance 1.2954)
			(thermal_gap 1.2954)
		)
		(pad "" np_thru_hole circle
			(at 10.700004 -2.990088 270)
			(size 0.254 0.254)
			(drill 2.2098)
			(layers "*.Cu" "*.Mask")
			(clearance 1.2954)
			(thermal_gap 1.2954)
		)
		(pad "" np_thru_hole circle
			(at 10.700004 9.009888 270)
			(size 0.254 0.254)
			(drill 2.2098)
			(layers "*.Cu" "*.Mask")
			(clearance 1.2954)
			(thermal_gap 1.2954)
		)
		(pad "" np_thru_hole circle
			(at 10.700004 21.010118 270)
			(size 0.254 0.254)
			(drill 2.2098)
			(layers "*.Cu" "*.Mask")
			(clearance 1.2954)
			(thermal_gap 1.2954)
		)
		(pad "1A1" thru_hole rect
			(at 0 0 270)
			(size 0.7874 0.7874)
			(drill 0.381)
			(layers "*.Cu" "*.Mask")
			(remove_unused_layers no)
			(net "TP_FM_QAT_CBL_PRSNT0_R_N")
			(clearance 0.1143)
			(thermal_gap 0.1143)
			(padstack
				(mode front_inner_back)
				(layer "Inner"
					(shape circle)
					(size 0.7874 0.7874)
					(clearance 0.1143)
				)
				(layer "B.Cu"
					(shape rect)
					(size 0.7874 0.7874)
					(clearance 0.1143)
				)
			)
		)
		(pad "1A2" thru_hole circle
			(at -1.400048 0.750062 270)
			(size 0.7874 0.7874)
			(drill 0.381)
			(layers "*.Cu" "*.Mask")
			(remove_unused_layers no)
			(net "SGPIO_PCH_SATA_CLOCK_R")
			(clearance 0.1143)
			(thermal_gap 0.1143)
		)
		(pad "1A3" thru_hole circle
			(at -0.700024 1.500124 270)
			(size 0.7874 0.7874)
			(drill 0.381)
			(layers "*.Cu" "*.Mask")
			(remove_unused_layers no)
			(net "GND")
			(clearance 0.1143)
			(thermal_gap 0.1143)
		)
		(pad "1A4" thru_hole circle
			(at 0 2.249932 270)
			(size 0.7874 0.7874)
			(drill 0.381)
			(layers "*.Cu" "*.Mask")
			(remove_unused_layers no)
			(net "SATA6G_P1_RX_C_DP")
			(clearance 0.1143)
			(thermal_gap 0.1143)
		)
		(pad "1A5" thru_hole circle
			(at -1.400048 2.999994 270)
			(size 0.7874 0.7874)
			(drill 0.381)
			(layers "*.Cu" "*.Mask")
			(remove_unused_layers no)
			(net "SATA6G_P1_RX_C_DN")
			(clearance 0.1143)
			(thermal_gap 0.1143)
		)
		(pad "1A6" thru_hole circle
			(at -0.700024 3.750056 270)
			(size 0.7874 0.7874)
			(drill 0.381)
			(layers "*.Cu" "*.Mask")
			(remove_unused_layers no)
			(net "GND")
			(clearance 0.1143)
			(thermal_gap 0.1143)
		)
		(pad "1A7" thru_hole circle
			(at 0 4.500118 270)
			(size 0.7874 0.7874)
			(drill 0.381)
			(layers "*.Cu" "*.Mask")
			(remove_unused_layers no)
			(net "SATA6G_P3_RX_C_DP")
			(clearance 0.1143)
			(thermal_gap 0.1143)
		)
		(pad "1A8" thru_hole circle
			(at -1.400048 5.249926 270)
			(size 0.7874 0.7874)
			(drill 0.381)
			(layers "*.Cu" "*.Mask")
			(remove_unused_layers no)
			(net "SATA6G_P3_RX_C_DN")
			(clearance 0.1143)
			(thermal_gap 0.1143)
		)
		(pad "1A9" thru_hole circle
			(at -0.700024 5.999988 270)
			(size 0.7874 0.7874)
			(drill 0.381)
			(layers "*.Cu" "*.Mask")
			(remove_unused_layers no)
			(net "GND")
			(clearance 0.1143)
			(thermal_gap 0.1143)
		)
		(pad "1B1" thru_hole circle
			(at 3.800094 0 270)
			(size 0.7874 0.7874)
			(drill 0.381)
			(layers "*.Cu" "*.Mask")
			(remove_unused_layers no)
			(net "GND")
			(clearance 0.1143)
			(thermal_gap 0.1143)
		)
		(pad "1B2" thru_hole circle
			(at 2.400046 0.750062 270)
			(size 0.7874 0.7874)
			(drill 0.381)
			(layers "*.Cu" "*.Mask")
			(remove_unused_layers no)
			(net "SGPIO_PCH_SATA_LOAD_R")
			(clearance 0.1143)
			(thermal_gap 0.1143)
		)
		(pad "1B3" thru_hole circle
			(at 3.10007 1.500124 270)
			(size 0.7874 0.7874)
			(drill 0.381)
			(layers "*.Cu" "*.Mask")
			(remove_unused_layers no)
			(net "GND")
			(clearance 0.1143)
			(thermal_gap 0.1143)
		)
		(pad "1B4" thru_hole circle
			(at 3.800094 2.249932 270)
			(size 0.7874 0.7874)
			(drill 0.381)
			(layers "*.Cu" "*.Mask")
			(remove_unused_layers no)
			(net "SATA6G_P0_RX_C_DP")
			(clearance 0.1143)
			(thermal_gap 0.1143)
		)
		(pad "1B5" thru_hole circle
			(at 2.400046 2.999994 270)
			(size 0.7874 0.7874)
			(drill 0.381)
			(layers "*.Cu" "*.Mask")
			(remove_unused_layers no)
			(net "SATA6G_P0_RX_C_DN")
			(clearance 0.1143)
			(thermal_gap 0.1143)
		)
		(pad "1B6" thru_hole circle
			(at 3.10007 3.750056 270)
			(size 0.7874 0.7874)
			(drill 0.381)
			(layers "*.Cu" "*.Mask")
			(remove_unused_layers no)
			(net "GND")
			(clearance 0.1143)
			(thermal_gap 0.1143)
		)
		(pad "1B7" thru_hole circle
			(at 3.800094 4.500118 270)
			(size 0.7874 0.7874)
			(drill 0.381)
			(layers "*.Cu" "*.Mask")
			(remove_unused_layers no)
			(net "SATA6G_P2_RX_C_DP")
			(clearance 0.1143)
			(thermal_gap 0.1143)
		)
		(pad "1B8" thru_hole circle
			(at 2.400046 5.249926 270)
			(size 0.7874 0.7874)
			(drill 0.381)
			(layers "*.Cu" "*.Mask")
			(remove_unused_layers no)
			(net "SATA6G_P2_RX_C_DN")
			(clearance 0.1143)
			(thermal_gap 0.1143)
		)
		(pad "1B9" thru_hole circle
			(at 3.10007 5.999988 270)
			(size 0.7874 0.7874)
			(drill 0.381)
			(layers "*.Cu" "*.Mask")
			(remove_unused_layers no)
			(net "GND")
			(clearance 0.1143)
			(thermal_gap 0.1143)
		)
		(pad "1C1" thru_hole circle
			(at 7.599934 0 270)
			(size 0.7874 0.7874)
			(drill 0.381)
			(layers "*.Cu" "*.Mask")
			(remove_unused_layers no)
			(net "SGPIO_PCH_SATA_DOUT0_R")
			(clearance 0.1143)
			(thermal_gap 0.1143)
		)
		(pad "1C2" thru_hole circle
			(at 6.199886 0.750062 270)
			(size 0.7874 0.7874)
			(drill 0.381)
			(layers "*.Cu" "*.Mask")
			(remove_unused_layers no)
			(net "GND")
			(clearance 0.1143)
			(thermal_gap 0.1143)
		)
		(pad "1C3" thru_hole circle
			(at 6.89991 1.500124 270)
			(size 0.7874 0.7874)
			(drill 0.381)
			(layers "*.Cu" "*.Mask")
			(remove_unused_layers no)
			(net "GND")
			(clearance 0.1143)
			(thermal_gap 0.1143)
		)
		(pad "1C4" thru_hole circle
			(at 7.599934 2.249932 270)
			(size 0.7874 0.7874)
			(drill 0.381)
			(layers "*.Cu" "*.Mask")
			(remove_unused_layers no)
			(net "SATA6G_P1_TX_C_DP")
			(clearance 0.1143)
			(thermal_gap 0.1143)
		)
		(pad "1C5" thru_hole circle
			(at 6.199886 2.999994 270)
			(size 0.7874 0.7874)
			(drill 0.381)
			(layers "*.Cu" "*.Mask")
			(remove_unused_layers no)
			(net "SATA6G_P1_TX_C_DN")
			(clearance 0.1143)
			(thermal_gap 0.1143)
		)
		(pad "1C6" thru_hole circle
			(at 6.89991 3.750056 270)
			(size 0.7874 0.7874)
			(drill 0.381)
			(layers "*.Cu" "*.Mask")
			(remove_unused_layers no)
			(net "GND")
			(clearance 0.1143)
			(thermal_gap 0.1143)
		)
		(pad "1C7" thru_hole circle
			(at 7.599934 4.500118 270)
			(size 0.7874 0.7874)
			(drill 0.381)
			(layers "*.Cu" "*.Mask")
			(remove_unused_layers no)
			(net "SATA6G_P3_TX_C_DP")
			(clearance 0.1143)
			(thermal_gap 0.1143)
		)
		(pad "1C8" thru_hole circle
			(at 6.199886 5.249926 270)
			(size 0.7874 0.7874)
			(drill 0.381)
			(layers "*.Cu" "*.Mask")
			(remove_unused_layers no)
			(net "SATA6G_P3_TX_C_DN")
			(clearance 0.1143)
			(thermal_gap 0.1143)
		)
		(pad "1C9" thru_hole circle
			(at 6.89991 5.999988 270)
			(size 0.7874 0.7874)
			(drill 0.381)
			(layers "*.Cu" "*.Mask")
			(remove_unused_layers no)
			(net "GND")
			(clearance 0.1143)
			(thermal_gap 0.1143)
		)
		(pad "1D1" thru_hole circle
			(at 11.400028 0 270)
			(size 0.7874 0.7874)
			(drill 0.381)
			(layers "*.Cu" "*.Mask")
			(remove_unused_layers no)
			(net "PU_DATAIN1_SATA_0_R")
			(clearance 0.1143)
			(thermal_gap 0.1143)
		)
		(pad "1D2" thru_hole circle
			(at 9.99998 0.750062 270)
			(size 0.7874 0.7874)
			(drill 0.381)
			(layers "*.Cu" "*.Mask")
			(remove_unused_layers no)
			(net "PD_SATA0_CONTROLLER_TYPE_R")
			(clearance 0.1143)
			(thermal_gap 0.1143)
		)
		(pad "1D3" thru_hole circle
			(at 10.700004 1.500124 270)
			(size 0.7874 0.7874)
			(drill 0.381)
			(layers "*.Cu" "*.Mask")
			(remove_unused_layers no)
			(net "GND")
			(clearance 0.1143)
			(thermal_gap 0.1143)
		)
		(pad "1D4" thru_hole circle
			(at 11.400028 2.249932 270)
			(size 0.7874 0.7874)
			(drill 0.381)
			(layers "*.Cu" "*.Mask")
			(remove_unused_layers no)
			(net "SATA6G_P0_TX_C_DP")
			(clearance 0.1143)
			(thermal_gap 0.1143)
		)
		(pad "1D5" thru_hole circle
			(at 9.99998 2.999994 270)
			(size 0.7874 0.7874)
			(drill 0.381)
			(layers "*.Cu" "*.Mask")
			(remove_unused_layers no)
			(net "SATA6G_P0_TX_C_DN")
			(clearance 0.1143)
			(thermal_gap 0.1143)
		)
		(pad "1D6" thru_hole circle
			(at 10.700004 3.750056 270)
			(size 0.7874 0.7874)
			(drill 0.381)
			(layers "*.Cu" "*.Mask")
			(remove_unused_layers no)
			(net "GND")
			(clearance 0.1143)
			(thermal_gap 0.1143)
		)
		(pad "1D7" thru_hole circle
			(at 11.400028 4.500118 270)
			(size 0.7874 0.7874)
			(drill 0.381)
			(layers "*.Cu" "*.Mask")
			(remove_unused_layers no)
			(net "SATA6G_P2_TX_C_DP")
			(clearance 0.1143)
			(thermal_gap 0.1143)
		)
		(pad "1D8" thru_hole circle
			(at 9.99998 5.249926 270)
			(size 0.7874 0.7874)
			(drill 0.381)
			(layers "*.Cu" "*.Mask")
			(remove_unused_layers no)
			(net "SATA6G_P2_TX_C_DN")
			(clearance 0.1143)
			(thermal_gap 0.1143)
		)
		(pad "1D9" thru_hole circle
			(at 10.700004 5.999988 270)
			(size 0.7874 0.7874)
			(drill 0.381)
			(layers "*.Cu" "*.Mask")
			(remove_unused_layers no)
			(net "GND")
			(clearance 0.1143)
			(thermal_gap 0.1143)
		)
		(pad "2A1" thru_hole circle
			(at 0 11.999976 270)
			(size 0.7874 0.7874)
			(drill 0.381)
			(layers "*.Cu" "*.Mask")
			(remove_unused_layers no)
			(net "TP_FM_QAT_CBL_PRSNT1_N_R")
			(clearance 0.1143)
			(thermal_gap 0.1143)
		)
		(pad "2A2" thru_hole circle
			(at -1.400048 12.750038 270)
			(size 0.7874 0.7874)
			(drill 0.381)
			(layers "*.Cu" "*.Mask")
			(remove_unused_layers no)
			(net "TP_SGPIO_SATA_CLOCK1_R")
			(clearance 0.1143)
			(thermal_gap 0.1143)
		)
		(pad "2A3" thru_hole circle
			(at -0.700024 13.5001 270)
			(size 0.7874 0.7874)
			(drill 0.381)
			(layers "*.Cu" "*.Mask")
			(remove_unused_layers no)
			(net "GND")
			(clearance 0.1143)
			(thermal_gap 0.1143)
		)
		(pad "2A4" thru_hole circle
			(at 0 14.249908 270)
			(size 0.7874 0.7874)
			(drill 0.381)
			(layers "*.Cu" "*.Mask")
			(remove_unused_layers no)
			(net "SATA6G_P5_RX_C_DP")
			(clearance 0.1143)
			(thermal_gap 0.1143)
		)
		(pad "2A5" thru_hole circle
			(at -1.400048 14.99997 270)
			(size 0.7874 0.7874)
			(drill 0.381)
			(layers "*.Cu" "*.Mask")
			(remove_unused_layers no)
			(net "SATA6G_P5_RX_C_DN")
			(clearance 0.1143)
			(thermal_gap 0.1143)
		)
		(pad "2A6" thru_hole circle
			(at -0.700024 15.750032 270)
			(size 0.7874 0.7874)
			(drill 0.381)
			(layers "*.Cu" "*.Mask")
			(remove_unused_layers no)
			(net "GND")
			(clearance 0.1143)
			(thermal_gap 0.1143)
		)
		(pad "2A7" thru_hole circle
			(at 0 16.500094 270)
			(size 0.7874 0.7874)
			(drill 0.381)
			(layers "*.Cu" "*.Mask")
			(remove_unused_layers no)
			(net "SATA6G_P7_RX_C_DP")
			(clearance 0.1143)
			(thermal_gap 0.1143)
		)
		(pad "2A8" thru_hole circle
			(at -1.400048 17.249902 270)
			(size 0.7874 0.7874)
			(drill 0.381)
			(layers "*.Cu" "*.Mask")
			(remove_unused_layers no)
			(net "SATA6G_P7_RX_C_DN")
			(clearance 0.1143)
			(thermal_gap 0.1143)
		)
		(pad "2A9" thru_hole circle
			(at -0.700024 17.999964 270)
			(size 0.7874 0.7874)
			(drill 0.381)
			(layers "*.Cu" "*.Mask")
			(remove_unused_layers no)
			(net "GND")
			(clearance 0.1143)
			(thermal_gap 0.1143)
		)
		(pad "2B1" thru_hole circle
			(at 3.800094 11.999976 270)
			(size 0.7874 0.7874)
			(drill 0.381)
			(layers "*.Cu" "*.Mask")
			(remove_unused_layers no)
			(net "GND")
			(clearance 0.1143)
			(thermal_gap 0.1143)
		)
		(pad "2B2" thru_hole circle
			(at 2.400046 12.750038 270)
			(size 0.7874 0.7874)
			(drill 0.381)
			(layers "*.Cu" "*.Mask")
			(remove_unused_layers no)
			(net "TP_SGPIO_SATA_LOAD1_R")
			(clearance 0.1143)
			(thermal_gap 0.1143)
		)
		(pad "2B3" thru_hole circle
			(at 3.10007 13.5001 270)
			(size 0.7874 0.7874)
			(drill 0.381)
			(layers "*.Cu" "*.Mask")
			(remove_unused_layers no)
			(net "GND")
			(clearance 0.1143)
			(thermal_gap 0.1143)
		)
		(pad "2B4" thru_hole circle
			(at 3.800094 14.249908 270)
			(size 0.7874 0.7874)
			(drill 0.381)
			(layers "*.Cu" "*.Mask")
			(remove_unused_layers no)
			(net "SATA6G_P4_RX_C_DP")
			(clearance 0.1143)
			(thermal_gap 0.1143)
		)
		(pad "2B5" thru_hole circle
			(at 2.400046 14.99997 270)
			(size 0.7874 0.7874)
			(drill 0.381)
			(layers "*.Cu" "*.Mask")
			(remove_unused_layers no)
			(net "SATA6G_P4_RX_C_DN")
			(clearance 0.1143)
			(thermal_gap 0.1143)
		)
		(pad "2B6" thru_hole circle
			(at 3.10007 15.750032 270)
			(size 0.7874 0.7874)
			(drill 0.381)
			(layers "*.Cu" "*.Mask")
			(remove_unused_layers no)
			(net "GND")
			(clearance 0.1143)
			(thermal_gap 0.1143)
		)
		(pad "2B7" thru_hole circle
			(at 3.800094 16.500094 270)
			(size 0.7874 0.7874)
			(drill 0.381)
			(layers "*.Cu" "*.Mask")
			(remove_unused_layers no)
			(net "SATA6G_P6_RX_C_DP")
			(clearance 0.1143)
			(thermal_gap 0.1143)
		)
		(pad "2B8" thru_hole circle
			(at 2.400046 17.249902 270)
			(size 0.7874 0.7874)
			(drill 0.381)
			(layers "*.Cu" "*.Mask")
			(remove_unused_layers no)
			(net "SATA6G_P6_RX_C_DN")
			(clearance 0.1143)
			(thermal_gap 0.1143)
		)
		(pad "2B9" thru_hole circle
			(at 3.10007 17.999964 270)
			(size 0.7874 0.7874)
			(drill 0.381)
			(layers "*.Cu" "*.Mask")
			(remove_unused_layers no)
			(net "GND")
			(clearance 0.1143)
			(thermal_gap 0.1143)
		)
		(pad "2C1" thru_hole circle
			(at 7.599934 11.999976 270)
			(size 0.7874 0.7874)
			(drill 0.381)
			(layers "*.Cu" "*.Mask")
			(remove_unused_layers no)
			(net "TP_SGPIO_SATA_DATA1_R")
			(clearance 0.1143)
			(thermal_gap 0.1143)
		)
		(pad "2C2" thru_hole circle
			(at 6.199886 12.750038 270)
			(size 0.7874 0.7874)
			(drill 0.381)
			(layers "*.Cu" "*.Mask")
			(remove_unused_layers no)
			(net "GND")
			(clearance 0.1143)
			(thermal_gap 0.1143)
		)
		(pad "2C3" thru_hole circle
			(at 6.89991 13.5001 270)
			(size 0.7874 0.7874)
			(drill 0.381)
			(layers "*.Cu" "*.Mask")
			(remove_unused_layers no)
			(net "GND")
			(clearance 0.1143)
			(thermal_gap 0.1143)
		)
		(pad "2C4" thru_hole circle
			(at 7.599934 14.249908 270)
			(size 0.7874 0.7874)
			(drill 0.381)
			(layers "*.Cu" "*.Mask")
			(remove_unused_layers no)
			(net "SATA6G_P5_TX_C_DP")
			(clearance 0.1143)
			(thermal_gap 0.1143)
		)
		(pad "2C5" thru_hole circle
			(at 6.199886 14.99997 270)
			(size 0.7874 0.7874)
			(drill 0.381)
			(layers "*.Cu" "*.Mask")
			(remove_unused_layers no)
			(net "SATA6G_P5_TX_C_DN")
			(clearance 0.1143)
			(thermal_gap 0.1143)
		)
		(pad "2C6" thru_hole circle
			(at 6.89991 15.750032 270)
			(size 0.7874 0.7874)
			(drill 0.381)
			(layers "*.Cu" "*.Mask")
			(remove_unused_layers no)
			(net "GND")
			(clearance 0.1143)
			(thermal_gap 0.1143)
		)
		(pad "2C7" thru_hole circle
			(at 7.599934 16.500094 270)
			(size 0.7874 0.7874)
			(drill 0.381)
			(layers "*.Cu" "*.Mask")
			(remove_unused_layers no)
			(net "SATA6G_P7_TX_C_DP")
			(clearance 0.1143)
			(thermal_gap 0.1143)
		)
		(pad "2C8" thru_hole circle
			(at 6.199886 17.249902 270)
			(size 0.7874 0.7874)
			(drill 0.381)
			(layers "*.Cu" "*.Mask")
			(remove_unused_layers no)
			(net "SATA6G_P7_TX_C_DN")
			(clearance 0.1143)
			(thermal_gap 0.1143)
		)
		(pad "2C9" thru_hole circle
			(at 6.89991 17.999964 270)
			(size 0.7874 0.7874)
			(drill 0.381)
			(layers "*.Cu" "*.Mask")
			(remove_unused_layers no)
			(net "GND")
			(clearance 0.1143)
			(thermal_gap 0.1143)
		)
		(pad "2D1" thru_hole circle
			(at 11.400028 11.999976 270)
			(size 0.7874 0.7874)
			(drill 0.381)
			(layers "*.Cu" "*.Mask")
			(remove_unused_layers no)
			(net "PU_DATAIN1_SATA_1_R")
			(clearance 0.1143)
			(thermal_gap 0.1143)
		)
		(pad "2D2" thru_hole circle
			(at 9.99998 12.750038 270)
			(size 0.7874 0.7874)
			(drill 0.381)
			(layers "*.Cu" "*.Mask")
			(remove_unused_layers no)
			(net "PD_SATA1_CONTROLLER_TYPE_R")
			(clearance 0.1143)
			(thermal_gap 0.1143)
		)
		(pad "2D3" thru_hole circle
			(at 10.700004 13.5001 270)
			(size 0.7874 0.7874)
			(drill 0.381)
			(layers "*.Cu" "*.Mask")
			(remove_unused_layers no)
			(net "GND")
			(clearance 0.1143)
			(thermal_gap 0.1143)
		)
		(pad "2D4" thru_hole circle
			(at 11.400028 14.249908 270)
			(size 0.7874 0.7874)
			(drill 0.381)
			(layers "*.Cu" "*.Mask")
			(remove_unused_layers no)
			(net "SATA6G_P4_TX_C_DP")
			(clearance 0.1143)
			(thermal_gap 0.1143)
		)
		(pad "2D5" thru_hole circle
			(at 9.99998 14.99997 270)
			(size 0.7874 0.7874)
			(drill 0.381)
			(layers "*.Cu" "*.Mask")
			(remove_unused_layers no)
			(net "SATA6G_P4_TX_C_DN")
			(clearance 0.1143)
			(thermal_gap 0.1143)
		)
		(pad "2D6" thru_hole circle
			(at 10.700004 15.750032 270)
			(size 0.7874 0.7874)
			(drill 0.381)
			(layers "*.Cu" "*.Mask")
			(remove_unused_layers no)
			(net "GND")
			(clearance 0.1143)
			(thermal_gap 0.1143)
		)
		(pad "2D7" thru_hole circle
			(at 11.400028 16.500094 270)
			(size 0.7874 0.7874)
			(drill 0.381)
			(layers "*.Cu" "*.Mask")
			(remove_unused_layers no)
			(net "SATA6G_P6_TX_C_DP")
			(clearance 0.1143)
			(thermal_gap 0.1143)
		)
	)
)
